# S9S_MB_2U (Grand Teton) — schematic netlist excerpt (pin names and nets, part order shuffled) for the footprints in the layout excerpt that follows; sources: Cadence DE-HDL packaged netlist, KiCad conversion of 03242023_DA0F0TMBIJ0_F0T_Motherboard_J_brd_V01_OCP.brd

Q99  MOSFET_NCH_DUAL  NX6008NBKS IC  pkg SOT363XB  page 256
  S1  = GND
  G1  = RST_PLD_CPU1_DRAM_CD_N
  D1  = LED_RST_PLD_CPU1_DRAM_CD_N_D

R3507  Q_RES  10K 1% CHIP  pkg 0402LF  page 151 : A = GPU_FPGA_RST_R_N ; B = GND

(kicad_pcb
	(version 20260206)
	(generator "pcbnew")
	(generator_version "10.0")
	(general
		(thickness 1.6)
		(legacy_teardrops no)
	)
	(paper "A4")
	(title_block
		(title "03242023_DA0F0TMBIJ0_F0T_Motherboard_J_brd_V01_OCP.brd")
		(comment 1 "Grand Teton / footprints 2730-2731 of 6105")
	)
	(layers
		(0 "F.Cu" signal "TOP")
		(4 "In1.Cu" signal "GND")
		(6 "In2.Cu" signal "IN1")
		(8 "In3.Cu" signal "GND1")
		(10 "In4.Cu" signal "IN2")
		(12 "In5.Cu" signal "GND2")
		(14 "In6.Cu" signal "IN3")
		(16 "In7.Cu" signal "GND3")
		(18 "In8.Cu" signal "VCC")
		(20 "In9.Cu" signal "VCC1")
		(22 "In10.Cu" signal "GND4")
		(24 "In11.Cu" signal "IN4")
		(26 "In12.Cu" signal "GND5")
		(28 "In13.Cu" signal "IN5")
		(30 "In14.Cu" signal "GND6")
		(32 "In15.Cu" signal "IN6")
		(34 "In16.Cu" signal "GND7")
		(2 "B.Cu" signal "BOTTOM")
		(9 "F.Adhes" user "F.Adhesive")
		(11 "B.Adhes" user "B.Adhesive")
		(13 "F.Paste" user "Package Geometry/Pastemask Top")
		(15 "B.Paste" user "Package Geometry/Pastemask Bottom")
		(5 "F.SilkS" user "Ref Des/Silkscreen Top")
		(7 "B.SilkS" user "Ref Des/Silkscreen Bottom")
		(1 "F.Mask" user "Board Geometry/Soldermask Top")
		(3 "B.Mask" user "Board Geometry/Soldermask Bottom")
		(17 "Dwgs.User" user "User.Drawings")
		(19 "Cmts.User" user "User.Comments")
		(21 "Eco1.User" user "User.Eco1")
		(23 "Eco2.User" user "User.Eco2")
		(25 "Edge.Cuts" user "Board Geometry/Outline")
		(27 "Margin" user)
		(31 "F.CrtYd" user "Package Geometry/Place Bound Top")
		(29 "B.CrtYd" user "Package Geometry/Place Bound Bottom")
		(35 "F.Fab" user "Ref Des/Assembly Top")
		(33 "B.Fab" user "Ref Des/Assembly Bottom")
	)
	(footprint ""
		(layer "F.Cu")
		(at 120.36044 -428.107348)
		(property "Reference" "R3507"
			(at 0 0 0)
			(layer "F.SilkS")
			(hide yes)
			(effects
				(font
					(size 1.27 1.27)
				)
			)
		)
		(property "Value" ""
			(at 0 0 0)
			(layer "F.Fab")
			(effects
				(font
					(size 1.27 1.27)
				)
			)
		)
		(duplicate_pad_numbers_are_jumpers no)
		(fp_line
			(start -0.7874 -0.4064)
			(end 0.7874 -0.4064)
			(stroke
				(width 0.1524)
				(type default)
			)
			(layer "F.SilkS")
		)
		(fp_line
			(start -0.7874 0.4064)
			(end -0.7874 -0.4064)
			(stroke
				(width 0.1524)
				(type default)
			)
			(layer "F.SilkS")
		)
		(fp_line
			(start 0.7874 -0.4064)
			(end 0.7874 0.4064)
			(stroke
				(width 0.1524)
				(type default)
			)
			(layer "F.SilkS")
		)
		(fp_line
			(start 0.7874 0.4064)
			(end -0.7874 0.4064)
			(stroke
				(width 0.1524)
				(type default)
			)
			(layer "F.SilkS")
		)
		(fp_line
			(start -0.67945 -0.305054)
			(end -0.12065 -0.305054)
			(stroke
				(width 0.1)
				(type default)
			)
			(layer "F.Fab")
		)
		(fp_line
			(start -0.67945 0.3048)
			(end -0.67945 -0.305054)
			(stroke
				(width 0.1)
				(type default)
			)
			(layer "F.Fab")
		)
		(fp_line
			(start -0.12065 -0.305054)
			(end -0.12065 -0.2794)
			(stroke
				(width 0.1)
				(type default)
			)
			(layer "F.Fab")
		)
		(fp_line
			(start -0.12065 -0.2794)
			(end 0.12065 -0.2794)
			(stroke
				(width 0.1)
				(type default)
			)
			(layer "F.Fab")
		)
		(fp_line
			(start -0.12065 0.2794)
			(end -0.12065 0.3048)
			(stroke
				(width 0.1)
				(type default)
			)
			(layer "F.Fab")
		)
		(fp_line
			(start -0.12065 0.3048)
			(end -0.67945 0.3048)
			(stroke
				(width 0.1)
				(type default)
			)
			(layer "F.Fab")
		)
		(fp_line
			(start 0.120396 0.2794)
			(end -0.12065 0.2794)
			(stroke
				(width 0.1)
				(type default)
			)
			(layer "F.Fab")
		)
		(fp_line
			(start 0.120396 0.3048)
			(end 0.120396 0.2794)
			(stroke
				(width 0.1)
				(type default)
			)
			(layer "F.Fab")
		)
		(fp_line
			(start 0.12065 -0.3048)
			(end 0.67945 -0.3048)
			(stroke
				(width 0.1)
				(type default)
			)
			(layer "F.Fab")
		)
		(fp_line
			(start 0.12065 -0.2794)
			(end 0.12065 -0.3048)
			(stroke
				(width 0.1)
				(type default)
			)
			(layer "F.Fab")
		)
		(fp_line
			(start 0.67945 -0.3048)
			(end 0.67945 0.3048)
			(stroke
				(width 0.1)
				(type default)
			)
			(layer "F.Fab")
		)
		(fp_line
			(start 0.67945 0.3048)
			(end 0.120396 0.3048)
			(stroke
				(width 0.1)
				(type default)
			)
			(layer "F.Fab")
		)
		(pad "1" smd circle
			(at -0.40005 0)
			(size 0 0)
			(layers "F.Cu" "F.Mask" "F.Paste")
			(net "GPU_FPGA_RST_R_N")
		)
		(pad "2" smd circle
			(at 0.40005 0)
			(size 0 0)
			(layers "F.Cu" "F.Mask" "F.Paste")
			(net "GND")
		)
	)
	(footprint ""
		(layer "F.Cu")
		(at 85.626194 -99.477322 180)
		(property "Reference" "Q99"
			(at 2.758948 0.66802 0)
			(unlocked yes)
			(layer "F.SilkS")
			(effects
				(font
					(size 0.7874 0.5842)
					(thickness 0.1524)
				)
			)
		)
		(property "Value" ""
			(at 0 0 180)
			(layer "F.Fab")
			(effects
				(font
					(size 1.27 1.27)
				)
			)
		)
		(duplicate_pad_numbers_are_jumpers no)
		(fp_line
			(start 1.376172 1.199896)
			(end -1.376172 1.199896)
			(stroke
				(width 0.1524)
				(type default)
			)
			(layer "F.SilkS")
		)
		(fp_line
			(start 1.376172 -1.199896)
			(end 1.376172 1.199896)
			(stroke
				(width 0.1524)
				(type default)
			)
			(layer "F.SilkS")
		)
		(fp_line
			(start 0.508 -1.199896)
			(end 1.376172 -1.199896)
			(stroke
				(width 0.1524)
				(type default)
			)
			(layer "F.SilkS")
		)
		(fp_line
			(start 0 -0.762)
			(end 0.508 -1.199896)
			(stroke
				(width 0.1524)
				(type default)
			)
			(layer "F.SilkS")
		)
		(fp_line
			(start -0.508 -1.199896)
			(end 0 -0.762)
			(stroke
				(width 0.1524)
				(type default)
			)
			(layer "F.SilkS")
		)
		(fp_line
			(start -1.376172 1.199896)
			(end -1.376172 -1.199896)
			(stroke
				(width 0.1524)
				(type default)
			)
			(layer "F.SilkS")
		)
		(fp_line
			(start -1.376172 -1.199896)
			(end -0.508 -1.199896)
			(stroke
				(width 0.1524)
				(type default)
			)
			(layer "F.SilkS")
		)
		(fp_poly
			(pts
				(xy -1.96596 -0.82042) (xy -2.72796 -0.43942) (xy -2.72796 -1.20142)
			)
			(stroke
				(width 0)
				(type default)
			)
			(fill yes)
			(layer "F.SilkS")
		)
		(fp_line
			(start 0.674878 1.100074)
			(end -0.674878 1.100074)
			(stroke
				(width 0.1)
				(type default)
			)
			(layer "F.Fab")
		)
		(fp_line
			(start 0.674878 -1.100074)
			(end 0.674878 1.100074)
			(stroke
				(width 0.1)
				(type default)
			)
			(layer "F.Fab")
		)
		(fp_line
			(start -0.674878 1.100074)
			(end -0.674878 -1.100074)
			(stroke
				(width 0.1)
				(type default)
			)
			(layer "F.Fab")
		)
		(fp_line
			(start -0.674878 -1.100074)
			(end 0.674878 -1.100074)
			(stroke
				(width 0.1)
				(type default)
			)
			(layer "F.Fab")
		)
		(fp_poly
			(pts
				(xy -1.4605 -0.7493) (xy -2.2225 -1.1303) (xy -2.2225 -0.3683)
			)
			(stroke
				(width 0)
				(type default)
			)
			(fill yes)
			(layer "F.Fab")
		)
		(pad "1" smd rect
			(at -0.899922 -0.750062 90)
			(size 0.6096 0.6096)
			(layers "F.Cu" "F.Mask" "F.Paste")
			(net "GND")
		)
		(pad "2" smd rect
			(at -0.899922 0 90)
			(size 0.4064 0.6096)
			(layers "F.Cu" "F.Mask" "F.Paste")
			(net "RST_PLD_CPU1_DRAM_CD_N")
		)
		(pad "3" smd rect
			(at -0.899922 0.750062 90)
			(size 0.6096 0.6096)
			(layers "F.Cu" "F.Mask" "F.Paste")
			(net "Net_1464")
		)
		(pad "4" smd rect
			(at 0.899922 0.750062 90)
			(size 0.6096 0.6096)
			(layers "F.Cu" "F.Mask" "F.Paste")
			(net "Net_1466")
		)
		(pad "5" smd rect
			(at 0.899922 0 90)
			(size 0.4064 0.6096)
			(layers "F.Cu" "F.Mask" "F.Paste")
			(net "Net_1465")
		)
		(pad "6" smd rect
			(at 0.899922 -0.750062 90)
			(size 0.6096 0.6096)
			(layers "F.Cu" "F.Mask" "F.Paste")
			(net "LED_RST_PLD_CPU1_DRAM_CD_N_D")
		)
	)
)
